Created on Valor NPI 9.6 Update 2 - Netlist Compare Summary.
DATE :  22 Jun 2017
TIME :  18:05:40


     MISMATCH SUMMARY REPORT
     -----------------------

Job  : 17301-sa-gerber         Job  : 17301-sa-gerber
Step : gerber                  Step : gerber
Type : CAD                     Type : CURCAD

-----------------------------------------------

 Mismatch Type: shorted


 Total : 0
-----------------------------------------------

 Mismatch Type: broken


 Total : 0
-----------------------------------------------

 Mismatch Type: missing


 Total : 0
-----------------------------------------------

 Mismatch Type: extra


 Total : 0
-----------------------------------------------
